# BASEBOARD_FAB2 (Tioga Pass) — schematic netlist excerpt (pin names and nets, part order shuffled) for the footprints in the layout excerpt that follows; sources: Cadence DE-HDL packaged netlist, KiCad conversion of Wiwynn_Tioga_Pass_MB.brd

C2U12  CAP  0.22UF 16V 10% X7R  pkg 0402  page 107 : A = P3E_CPU0_PE1_PCH_RXN<4> ; B = P3E_CPU0_PE1_SS_RXN<4>
R6L6  RES  0.0 5% CHIP  pkg 0402  page 230 : A = PVDDQ_KLM ; B = VSENSE_PVDDQ_KLM_VTT

U7E3  TTL1G08  NC7SZ08 IC  pkg SOTLF  page 95
  A(0)  = FM_PVCCIN_CPU1_PWR_IN_ALERT_N
  B(0)  = IRQ_PVCCIN_CPU1_VRHOT_LVC3_N
  Y(0)  = IRQ_CPU1_PROCHOT_G_N

(kicad_pcb
	(version 20260206)
	(generator "pcbnew")
	(generator_version "10.0")
	(general
		(thickness 1.6)
		(legacy_teardrops no)
	)
	(paper "A4")
	(title_block
		(title "Wiwynn_Tioga_Pass_MB.brd")
		(comment 1 "Tioga Pass / footprints 2431-2433 of 4770")
	)
	(layers
		(0 "F.Cu" signal "TOP")
		(4 "In1.Cu" signal "L2GND")
		(6 "In2.Cu" signal "L3")
		(8 "In3.Cu" signal "L4GND")
		(10 "In4.Cu" signal "L5")
		(12 "In5.Cu" signal "L6GND")
		(14 "In6.Cu" signal "L7VCC")
		(16 "In7.Cu" signal "L8VCC")
		(18 "In8.Cu" signal "L9GND")
		(20 "In9.Cu" signal "L10")
		(22 "In10.Cu" signal "L11GND")
		(24 "In11.Cu" signal "L12")
		(26 "In12.Cu" signal "L13GND")
		(2 "B.Cu" signal "BOTTOM")
		(9 "F.Adhes" user "F.Adhesive")
		(11 "B.Adhes" user "B.Adhesive")
		(13 "F.Paste" user "Package Geometry/Pastemask Top")
		(15 "B.Paste" user "Package Geometry/Pastemask Bottom")
		(5 "F.SilkS" user "Ref Des/Silkscreen Top")
		(7 "B.SilkS" user "Ref Des/Silkscreen Bottom")
		(1 "F.Mask" user "Board Geometry/Soldermask Top")
		(3 "B.Mask" user "Board Geometry/Soldermask Bottom")
		(17 "Dwgs.User" user "User.Drawings")
		(19 "Cmts.User" user "User.Comments")
		(21 "Eco1.User" user "User.Eco1")
		(23 "Eco2.User" user "User.Eco2")
		(25 "Edge.Cuts" user "Board Geometry/Outline")
		(27 "Margin" user)
		(31 "F.CrtYd" user "Package Geometry/Place Bound Top")
		(29 "B.CrtYd" user "Package Geometry/Place Bound Bottom")
		(35 "F.Fab" user "Ref Des/Assembly Top")
		(33 "B.Fab" user "Ref Des/Assembly Bottom")
	)
	(footprint ""
		(layer "B.Cu")
		(at 376.418348 -47.007018 180)
		(property "Reference" "U7E3"
			(at -2.286 -1.281684 0)
			(unlocked yes)
			(layer "B.SilkS")
			(effects
				(font
					(size 0.7874 0.5842)
					(thickness 0.1524)
				)
				(justify left mirror)
			)
		)
		(property "Value" ""
			(at 0 0 0)
			(layer "B.Fab")
			(effects
				(font
					(size 1.27 1.27)
				)
				(justify mirror)
			)
		)
		(duplicate_pad_numbers_are_jumpers no)
		(fp_circle
			(center 0.402844 -0.6604)
			(end 0.275844 -0.6604)
			(stroke
				(width 0.254)
				(type default)
			)
			(fill no)
			(layer "B.SilkS")
		)
		(fp_poly
			(pts
				(xy -0.21463 -0.450088) (xy -1.56337 -0.450088) (xy -1.56337 1.75006) (xy -0.21463 1.75006)
			)
			(stroke
				(width 0)
				(type default)
			)
			(fill no)
			(layer "B.CrtYd")
		)
		(fp_line
			(start -0.21463 1.75006)
			(end -0.21463 -0.450088)
			(stroke
				(width 0.1)
				(type default)
			)
			(layer "B.Fab")
		)
		(fp_line
			(start -0.21463 -0.450088)
			(end -1.56337 -0.450088)
			(stroke
				(width 0.1)
				(type default)
			)
			(layer "B.Fab")
		)
		(fp_line
			(start -1.56337 1.75006)
			(end -0.21463 1.75006)
			(stroke
				(width 0.1)
				(type default)
			)
			(layer "B.Fab")
		)
		(fp_line
			(start -1.56337 -0.450088)
			(end -1.56337 1.75006)
			(stroke
				(width 0.1)
				(type default)
			)
			(layer "B.Fab")
		)
		(fp_circle
			(center 0.4699 -0.8382)
			(end 0.3429 -0.8382)
			(stroke
				(width 0.254)
				(type default)
			)
			(fill no)
			(layer "B.Fab")
		)
		(pad "1" smd rect
			(at 0 0)
			(size 1.016 0.381)
			(layers "B.Cu" "B.Mask" "B.Paste")
			(net "FM_PVCCIN_CPU1_PWR_IN_ALERT_N")
		)
		(pad "2" smd rect
			(at 0 0.649986)
			(size 1.016 0.381)
			(layers "B.Cu" "B.Mask" "B.Paste")
			(net "IRQ_PVCCIN_CPU1_VRHOT_LVC3_N")
		)
		(pad "3" smd rect
			(at 0 1.299972)
			(size 1.016 0.381)
			(layers "B.Cu" "B.Mask" "B.Paste")
			(net "GND")
		)
		(pad "4" smd rect
			(at -1.778 1.299972)
			(size 1.016 0.381)
			(layers "B.Cu" "B.Mask" "B.Paste")
			(net "IRQ_CPU1_PROCHOT_G_N")
		)
		(pad "5" smd rect
			(at -1.778 0)
			(size 1.016 0.381)
			(layers "B.Cu" "B.Mask" "B.Paste")
			(net "P3V3_STBY")
		)
	)
	(footprint ""
		(layer "B.Cu")
		(at 345.919806 -61.257434)
		(property "Reference" "C2U12"
			(at 0 0 0)
			(layer "B.SilkS")
			(hide yes)
			(effects
				(font
					(size 1.27 1.27)
				)
				(justify mirror)
			)
		)
		(property "Value" ""
			(at 0 0 0)
			(layer "B.Fab")
			(effects
				(font
					(size 1.27 1.27)
				)
				(justify mirror)
			)
		)
		(duplicate_pad_numbers_are_jumpers no)
		(fp_poly
			(pts
				(xy -0.3048 -0.1016) (xy -0.3048 0.9906) (xy 0.3048 0.9906) (xy 0.3048 -0.1016)
			)
			(stroke
				(width 0)
				(type default)
			)
			(fill no)
			(layer "B.CrtYd")
		)
		(fp_line
			(start -0.3048 -0.1016)
			(end 0.3048 -0.1016)
			(stroke
				(width 0.1)
				(type default)
			)
			(layer "B.Fab")
		)
		(fp_line
			(start -0.3048 0.9906)
			(end -0.3048 -0.1016)
			(stroke
				(width 0.1)
				(type default)
			)
			(layer "B.Fab")
		)
		(fp_line
			(start 0.3048 -0.1016)
			(end 0.3048 0.9906)
			(stroke
				(width 0.1)
				(type default)
			)
			(layer "B.Fab")
		)
		(fp_line
			(start 0.3048 0.9906)
			(end -0.3048 0.9906)
			(stroke
				(width 0.1)
				(type default)
			)
			(layer "B.Fab")
		)
		(pad "1" smd rect
			(at 0 0 180)
			(size 0.508 0.508)
			(layers "B.Cu" "B.Mask" "B.Paste")
			(net "P3E_CPU0_PE1_PCH_RXN<4>")
		)
		(pad "2" smd rect
			(at 0 0.889 180)
			(size 0.508 0.508)
			(layers "B.Cu" "B.Mask" "B.Paste")
			(net "P3E_CPU0_PE1_SS_RXN<4>")
		)
		(zone
			(layer "B.Cu")
			(hatch none 0.5)
			(connect_pads
				(clearance 0)
			)
			(min_thickness 0.25)
			(keepout
				(tracks allowed)
				(vias not_allowed)
				(pads allowed)
				(copperpour not_allowed)
				(footprints allowed)
			)
			(placement
				(enabled no)
				(sheetname "")
			)
			(fill
				(thermal_gap 0.5)
				(thermal_bridge_width 0.5)
				(island_removal_mode 0)
			)
			(polygon
				(pts
					(xy 346.173806 -61.003434) (xy 345.665806 -61.003434) (xy 345.665806 -60.622434) (xy 346.173806 -60.622434)
				)
			)
		)
	)
	(footprint ""
		(layer "B.Cu")
		(at 171.1706 -147.8026 90)
		(property "Reference" "R6L6"
			(at 0 0 90)
			(layer "B.SilkS")
			(hide yes)
			(effects
				(font
					(size 1.27 1.27)
				)
				(justify mirror)
			)
		)
		(property "Value" ""
			(at 0 0 90)
			(layer "B.Fab")
			(effects
				(font
					(size 1.27 1.27)
				)
				(justify mirror)
			)
		)
		(duplicate_pad_numbers_are_jumpers no)
		(fp_rect
			(start 0.2794 0.9906)
			(end -0.2794 -0.1016)
			(stroke
				(width 0)
				(type default)
			)
			(fill no)
			(layer "B.CrtYd")
		)
		(fp_line
			(start 0.2794 -0.1016)
			(end 0.2794 0.9906)
			(stroke
				(width 0.1)
				(type default)
			)
			(layer "B.Fab")
		)
		(fp_line
			(start -0.2794 -0.1016)
			(end 0.2794 -0.1016)
			(stroke
				(width 0.1)
				(type default)
			)
			(layer "B.Fab")
		)
		(fp_line
			(start 0.2794 0.9906)
			(end -0.2794 0.9906)
			(stroke
				(width 0.1)
				(type default)
			)
			(layer "B.Fab")
		)
		(fp_line
			(start -0.2794 0.9906)
			(end -0.2794 -0.1016)
			(stroke
				(width 0.1)
				(type default)
			)
			(layer "B.Fab")
		)
		(pad "1" smd rect
			(at 0 0 270)
			(size 0.508 0.508)
			(layers "B.Cu" "B.Mask" "B.Paste")
			(net "PVDDQ_KLM")
		)
		(pad "2" smd rect
			(at 0 0.889 270)
			(size 0.508 0.508)
			(layers "B.Cu" "B.Mask" "B.Paste")
			(net "VSENSE_PVDDQ_KLM_VTT")
		)
		(zone
			(layer "B.Cu")
			(hatch none 0.5)
			(connect_pads
				(clearance 0)
			)
			(min_thickness 0.25)
			(keepout
				(tracks not_allowed)
				(vias allowed)
				(pads allowed)
				(copperpour not_allowed)
				(footprints allowed)
			)
			(placement
				(enabled no)
				(sheetname "")
			)
			(fill
				(thermal_gap 0.5)
				(thermal_bridge_width 0.5)
				(island_removal_mode 0)
			)
			(polygon
				(pts
					(xy 171.8056 -148.0566) (xy 171.4246 -148.0566) (xy 171.4246 -147.5486) (xy 171.8056 -147.5486)
				)
			)
		)
		(zone
			(layer "B.Cu")
			(hatch none 0.5)
			(connect_pads
				(clearance 0)
			)
			(min_thickness 0.25)
			(keepout
				(tracks allowed)
				(vias not_allowed)
				(pads allowed)
				(copperpour not_allowed)
				(footprints allowed)
			)
			(placement
				(enabled no)
				(sheetname "")
			)
			(fill
				(thermal_gap 0.5)
				(thermal_bridge_width 0.5)
				(island_removal_mode 0)
			)
			(polygon
				(pts
					(xy 171.8056 -148.0566) (xy 171.4246 -148.0566) (xy 171.4246 -147.5486) (xy 171.8056 -147.5486)
				)
			)
		)
	)
)
